(kicad_pcb
	(version 20260206)
	(generator "pcbnew")
	(generator_version "10.0")
	(general
		(thickness 1.6)
		(legacy_teardrops no)
	)
	(paper "A4")
	(title_block
		(title "Wiwynn_Tioga_Pass_MB.brd")
		(comment 1 "Tioga Pass / footprint 2035 of 4770 (U8D7), pads 1-108 of 256")
	)
	(layers
		(0 "F.Cu" signal "TOP")
		(4 "In1.Cu" signal "L2GND")
		(6 "In2.Cu" signal "L3")
		(8 "In3.Cu" signal "L4GND")
		(10 "In4.Cu" signal "L5")
		(12 "In5.Cu" signal "L6GND")
		(14 "In6.Cu" signal "L7VCC")
		(16 "In7.Cu" signal "L8VCC")
		(18 "In8.Cu" signal "L9GND")
		(20 "In9.Cu" signal "L10")
		(22 "In10.Cu" signal "L11GND")
		(24 "In11.Cu" signal "L12")
		(26 "In12.Cu" signal "L13GND")
		(2 "B.Cu" signal "BOTTOM")
		(9 "F.Adhes" user "F.Adhesive")
		(11 "B.Adhes" user "B.Adhesive")
		(13 "F.Paste" user "Package Geometry/Pastemask Top")
		(15 "B.Paste" user "Package Geometry/Pastemask Bottom")
		(5 "F.SilkS" user "Ref Des/Silkscreen Top")
		(7 "B.SilkS" user "Ref Des/Silkscreen Bottom")
		(1 "F.Mask" user "Board Geometry/Soldermask Top")
		(3 "B.Mask" user "Board Geometry/Soldermask Bottom")
		(17 "Dwgs.User" user "User.Drawings")
		(19 "Cmts.User" user "User.Comments")
		(21 "Eco1.User" user "User.Eco1")
		(23 "Eco2.User" user "User.Eco2")
		(25 "Edge.Cuts" user "Board Geometry/Outline")
		(27 "Margin" user)
		(31 "F.CrtYd" user "Package Geometry/Place Bound Top")
		(29 "B.CrtYd" user "Package Geometry/Place Bound Bottom")
		(35 "F.Fab" user "Ref Des/Assembly Top")
		(33 "B.Fab" user "Ref Des/Assembly Bottom")
	)
	(footprint ""
		(layer "F.Cu")
		(at 372.745 -74.295 180)
		(property "Reference" "U8D7"
			(at -0.635 -8.28167 0)
			(unlocked yes)
			(layer "F.SilkS")
			(effects
				(font
					(size 0.7874 0.5842)
					(thickness 0.1524)
				)
			)
		)
		(property "Value" ""
			(at 0 0 180)
			(layer "F.Fab")
			(effects
				(font
					(size 1.27 1.27)
				)
			)
		)
		(duplicate_pad_numbers_are_jumpers no)
		(pad "A1" smd circle
			(at -5.999988 -5.999988 180)
			(size 0.3556 0.3556)
			(layers "F.Cu" "F.Mask" "F.Paste")
			(net "P3V3_STBY")
		)
		(pad "A2" smd circle
			(at -5.199888 -5.999988 180)
			(size 0.3556 0.3556)
			(layers "F.Cu" "F.Mask" "F.Paste")
			(net "Net_344")
		)
		(pad "A3" smd circle
			(at -4.400042 -5.999988 180)
			(size 0.3556 0.3556)
			(layers "F.Cu" "F.Mask" "F.Paste")
			(net "FM_PCH_PRSNT_N")
		)
		(pad "A4" smd circle
			(at -3.599942 -5.999988 180)
			(size 0.3556 0.3556)
			(layers "F.Cu" "F.Mask" "F.Paste")
			(net "FM_P3V3_CPLD_EN")
		)
		(pad "A5" smd circle
			(at -2.800096 -5.999988 180)
			(size 0.3556 0.3556)
			(layers "F.Cu" "F.Mask" "F.Paste")
			(net "TP_CPLD1_PT11A")
		)
		(pad "A6" smd circle
			(at -1.999996 -5.999988 180)
			(size 0.3556 0.3556)
			(layers "F.Cu" "F.Mask" "F.Paste")
			(net "JTAG_PLD_TDI")
		)
		(pad "A7" smd circle
			(at -1.199896 -5.999988 180)
			(size 0.3556 0.3556)
			(layers "F.Cu" "F.Mask" "F.Paste")
			(net "JTAG_PLD_TCK")
		)
		(pad "A8" smd circle
			(at -0.40005 -5.999988 180)
			(size 0.3556 0.3556)
			(layers "F.Cu" "F.Mask" "F.Paste")
			(net "TP_CPLD1_PT17B_PCLKC0_1")
		)
		(pad "A9" smd circle
			(at 0.40005 -5.999988 180)
			(size 0.3556 0.3556)
			(layers "F.Cu" "F.Mask" "F.Paste")
			(net "SMB_SENSOR_STBY_LVC3_SCL")
		)
		(pad "A10" smd circle
			(at 1.199896 -5.999988 180)
			(size 0.3556 0.3556)
			(layers "F.Cu" "F.Mask" "F.Paste")
			(net "FM_PVCCIN_PVCCSA_CPU0_EN_LVC1")
		)
		(pad "A11" smd circle
			(at 1.999996 -5.999988 180)
			(size 0.3556 0.3556)
			(layers "F.Cu" "F.Mask" "F.Paste")
			(net "FM_CPU0_OR_CPU1_MCP_PRES")
		)
		(pad "A12" smd circle
			(at 2.800096 -5.999988 180)
			(size 0.3556 0.3556)
			(layers "F.Cu" "F.Mask" "F.Paste")
			(net "PU_THERMTRIP_FORCE_N")
		)
		(pad "A13" smd circle
			(at 3.599942 -5.999988 180)
			(size 0.3556 0.3556)
			(layers "F.Cu" "F.Mask" "F.Paste")
			(net "TP_CPLD1_PT24C_INITN")
		)
		(pad "A14" smd circle
			(at 4.400042 -5.999988 180)
			(size 0.3556 0.3556)
			(layers "F.Cu" "F.Mask" "F.Paste")
			(net "TP_CPLD1_PT22D")
		)
		(pad "A15" smd circle
			(at 5.199888 -5.999988 180)
			(size 0.3556 0.3556)
			(layers "F.Cu" "F.Mask" "F.Paste")
			(net "TP_CPLD1_PT24B")
		)
		(pad "A16" smd circle
			(at 5.999988 -5.999988 180)
			(size 0.3556 0.3556)
			(layers "F.Cu" "F.Mask" "F.Paste")
			(net "P3V3_STBY")
		)
		(pad "B1" smd circle
			(at -5.999988 -5.199888 180)
			(size 0.3556 0.3556)
			(layers "F.Cu" "F.Mask" "F.Paste")
			(net "RST_PCIE_PCH_PERST_N")
		)
		(pad "B2" smd circle
			(at -5.199888 -5.199888 180)
			(size 0.3556 0.3556)
			(layers "F.Cu" "F.Mask" "F.Paste")
			(net "GND")
		)
		(pad "B3" smd circle
			(at -4.400042 -5.199888 180)
			(size 0.3556 0.3556)
			(layers "F.Cu" "F.Mask" "F.Paste")
			(net "FM_CTNR_PS_ON")
		)
		(pad "B4" smd circle
			(at -3.599942 -5.199888 180)
			(size 0.3556 0.3556)
			(layers "F.Cu" "F.Mask" "F.Paste")
			(net "PWRGD_PVTT_CPU0")
		)
		(pad "B5" smd circle
			(at -2.800096 -5.199888 180)
			(size 0.3556 0.3556)
			(layers "F.Cu" "F.Mask" "F.Paste")
			(net "PWRGD_P12V_MAIN")
		)
		(pad "B6" smd circle
			(at -1.999996 -5.199888 180)
			(size 0.3556 0.3556)
			(layers "F.Cu" "F.Mask" "F.Paste")
			(net "TP_CPLD1_PT11B")
		)
		(pad "B7" smd circle
			(at -1.199896 -5.199888 180)
			(size 0.3556 0.3556)
			(layers "F.Cu" "F.Mask" "F.Paste")
			(net "TP_CPLD1_PT13A")
		)
		(pad "B8" smd circle
			(at -0.40005 -5.199888 180)
			(size 0.3556 0.3556)
			(layers "F.Cu" "F.Mask" "F.Paste")
			(net "JTAG_PLD_TMS")
		)
		(pad "B9" smd circle
			(at 0.40005 -5.199888 180)
			(size 0.3556 0.3556)
			(layers "F.Cu" "F.Mask" "F.Paste")
			(net "PU_RST_PERST_BIT1")
		)
		(pad "B10" smd circle
			(at 1.199896 -5.199888 180)
			(size 0.3556 0.3556)
			(layers "F.Cu" "F.Mask" "F.Paste")
			(net "PU_CPLD1_PT20D_PROGRAMN")
		)
		(pad "B11" smd circle
			(at 1.999996 -5.199888 180)
			(size 0.3556 0.3556)
			(layers "F.Cu" "F.Mask" "F.Paste")
			(net "PWRGD_DSW_PWROK")
		)
		(pad "B12" smd circle
			(at 2.800096 -5.199888 180)
			(size 0.3556 0.3556)
			(layers "F.Cu" "F.Mask" "F.Paste")
			(net "FM_PCH_PWRBTN_R1_N")
		)
		(pad "B13" smd circle
			(at 3.599942 -5.199888 180)
			(size 0.3556 0.3556)
			(layers "F.Cu" "F.Mask" "F.Paste")
			(net "TP_CPLD1_PT22C")
		)
		(pad "B14" smd circle
			(at 4.400042 -5.199888 180)
			(size 0.3556 0.3556)
			(layers "F.Cu" "F.Mask" "F.Paste")
			(net "FM_SINT_PRSNT_N")
		)
		(pad "B15" smd circle
			(at 5.199888 -5.199888 180)
			(size 0.3556 0.3556)
			(layers "F.Cu" "F.Mask" "F.Paste")
			(net "GND")
		)
		(pad "B16" smd circle
			(at 5.999988 -5.199888 180)
			(size 0.3556 0.3556)
			(layers "F.Cu" "F.Mask" "F.Paste")
			(net "FM_ADR_COMPLETE_DLY")
		)
		(pad "C1" smd circle
			(at -5.999988 -4.400042 180)
			(size 0.3556 0.3556)
			(layers "F.Cu" "F.Mask" "F.Paste")
			(net "RST_PCIE_CPU_DEV1_N")
		)
		(pad "C2" smd circle
			(at -5.199888 -4.400042 180)
			(size 0.3556 0.3556)
			(layers "F.Cu" "F.Mask" "F.Paste")
			(net "FM_PCH_PLD_DATA")
		)
		(pad "C3" smd circle
			(at -4.400042 -4.400042 180)
			(size 0.3556 0.3556)
			(layers "F.Cu" "F.Mask" "F.Paste")
			(net "GND")
		)
		(pad "C4" smd circle
			(at -3.599942 -4.400042 180)
			(size 0.3556 0.3556)
			(layers "F.Cu" "F.Mask" "F.Paste")
			(net "FM_ADR_SMI_GPIO_R_N")
		)
		(pad "C5" smd circle
			(at -2.800096 -4.400042 180)
			(size 0.3556 0.3556)
			(layers "F.Cu" "F.Mask" "F.Paste")
			(net "FM_CPU1_THERMTRIP_LATCH_LVT3_N")
		)
		(pad "C6" smd circle
			(at -1.999996 -4.400042 180)
			(size 0.3556 0.3556)
			(layers "F.Cu" "F.Mask" "F.Paste")
			(net "JTAG_PLD_TDO")
		)
		(pad "C7" smd circle
			(at -1.199896 -4.400042 180)
			(size 0.3556 0.3556)
			(layers "F.Cu" "F.Mask" "F.Paste")
			(net "FM_BMC_ONCTL_N")
		)
		(pad "C8" smd circle
			(at -0.40005 -4.400042 180)
			(size 0.3556 0.3556)
			(layers "F.Cu" "F.Mask" "F.Paste")
			(net "FM_ADR_COMPLETE")
		)
		(pad "C9" smd circle
			(at 0.40005 -4.400042 180)
			(size 0.3556 0.3556)
			(layers "F.Cu" "F.Mask" "F.Paste")
			(net "SMB_SENSOR_STBY_LVC3_SDA")
		)
		(pad "C10" smd circle
			(at 1.199896 -4.400042 180)
			(size 0.3556 0.3556)
			(layers "F.Cu" "F.Mask" "F.Paste")
			(net "FM_JTAG_PLD_EN_DEBUG")
		)
		(pad "C11" smd circle
			(at 1.999996 -4.400042 180)
			(size 0.3556 0.3556)
			(layers "F.Cu" "F.Mask" "F.Paste")
			(net "FM_CPU0_CD_PRES")
		)
		(pad "C12" smd circle
			(at 2.800096 -4.400042 180)
			(size 0.3556 0.3556)
			(layers "F.Cu" "F.Mask" "F.Paste")
			(net "FM_SLPS4_N")
		)
		(pad "C13" smd circle
			(at 3.599942 -4.400042 180)
			(size 0.3556 0.3556)
			(layers "F.Cu" "F.Mask" "F.Paste")
			(net "TP_CPLD1_PT24D_DONE")
		)
		(pad "C14" smd circle
			(at 4.400042 -4.400042 180)
			(size 0.3556 0.3556)
			(layers "F.Cu" "F.Mask" "F.Paste")
			(net "GND")
		)
		(pad "C15" smd circle
			(at 5.199888 -4.400042 180)
			(size 0.3556 0.3556)
			(layers "F.Cu" "F.Mask" "F.Paste")
			(net "FM_DB1200_PWRGD")
		)
		(pad "C16" smd circle
			(at 5.999988 -4.400042 180)
			(size 0.3556 0.3556)
			(layers "F.Cu" "F.Mask" "F.Paste")
			(net "PWRGD_PCH_PWROK")
		)
		(pad "D1" smd circle
			(at -5.999988 -3.599942 180)
			(size 0.3556 0.3556)
			(layers "F.Cu" "F.Mask" "F.Paste")
			(net "TP_CPLD1_PL1B_L_GPLLC_FB")
		)
		(pad "D2" smd circle
			(at -5.199888 -3.599942 180)
			(size 0.3556 0.3556)
			(layers "F.Cu" "F.Mask" "F.Paste")
			(net "FM_MEM_EVENT_FUNC")
		)
		(pad "D3" smd circle
			(at -4.400042 -3.599942 180)
			(size 0.3556 0.3556)
			(layers "F.Cu" "F.Mask" "F.Paste")
			(net "TP_CPLD1_PL1A_L_GPLLT_FB")
		)
		(pad "D4" smd circle
			(at -3.599942 -3.599942 180)
			(size 0.3556 0.3556)
			(layers "F.Cu" "F.Mask" "F.Paste")
			(net "GND")
		)
		(pad "D5" smd circle
			(at -2.800096 -3.599942 180)
			(size 0.3556 0.3556)
			(layers "F.Cu" "F.Mask" "F.Paste")
			(net "P3V3_STBY")
		)
		(pad "D6" smd circle
			(at -1.999996 -3.599942 180)
			(size 0.3556 0.3556)
			(layers "F.Cu" "F.Mask" "F.Paste")
			(net "RST_PCIE_CPU_DEV0_N")
		)
		(pad "D7" smd circle
			(at -1.199896 -3.599942 180)
			(size 0.3556 0.3556)
			(layers "F.Cu" "F.Mask" "F.Paste")
			(net "FM_FORCE_ADR_N")
		)
		(pad "D8" smd circle
			(at -0.40005 -3.599942 180)
			(size 0.3556 0.3556)
			(layers "F.Cu" "F.Mask" "F.Paste")
			(net "TP_CPLD1_PT17C")
		)
		(pad "D9" smd circle
			(at 0.40005 -3.599942 180)
			(size 0.3556 0.3556)
			(layers "F.Cu" "F.Mask" "F.Paste")
			(net "RST_PCIE_MIDPLANE_N")
		)
		(pad "D10" smd circle
			(at 1.199896 -3.599942 180)
			(size 0.3556 0.3556)
			(layers "F.Cu" "F.Mask" "F.Paste")
			(net "TP_CPLD1_PT20A")
		)
		(pad "D11" smd circle
			(at 1.999996 -3.599942 180)
			(size 0.3556 0.3556)
			(layers "F.Cu" "F.Mask" "F.Paste")
			(net "FM_CPU0_AND_CPU1_MCP_PRES")
		)
		(pad "D12" smd circle
			(at 2.800096 -3.599942 180)
			(size 0.3556 0.3556)
			(layers "F.Cu" "F.Mask" "F.Paste")
			(net "P3V3_STBY")
		)
		(pad "D13" smd circle
			(at 3.599942 -3.599942 180)
			(size 0.3556 0.3556)
			(layers "F.Cu" "F.Mask" "F.Paste")
			(net "GND")
		)
		(pad "D14" smd circle
			(at 4.400042 -3.599942 180)
			(size 0.3556 0.3556)
			(layers "F.Cu" "F.Mask" "F.Paste")
			(net "PWRGD_SYS_PWROK")
		)
		(pad "D15" smd circle
			(at 5.199888 -3.599942 180)
			(size 0.3556 0.3556)
			(layers "F.Cu" "F.Mask" "F.Paste")
			(net "PWRGD_P1V8MCP_CPU0")
		)
		(pad "D16" smd circle
			(at 5.999988 -3.599942 180)
			(size 0.3556 0.3556)
			(layers "F.Cu" "F.Mask" "F.Paste")
			(net "PWRGD_P1V8MCP_CPU1")
		)
		(pad "E1" smd circle
			(at -5.999988 -2.800096 180)
			(size 0.3556 0.3556)
			(layers "F.Cu" "F.Mask" "F.Paste")
			(net "CLK_32K_SUSCLK_PLD")
		)
		(pad "E2" smd circle
			(at -5.199888 -2.800096 180)
			(size 0.3556 0.3556)
			(layers "F.Cu" "F.Mask" "F.Paste")
			(net "FM_CPU_CATERR_DLY_LVT3_N")
		)
		(pad "E3" smd circle
			(at -4.400042 -2.800096 180)
			(size 0.3556 0.3556)
			(layers "F.Cu" "F.Mask" "F.Paste")
			(net "TP_CPLD1_PL2B_L_GPLLC_IN")
		)
		(pad "E4" smd circle
			(at -3.599942 -2.800096 180)
			(size 0.3556 0.3556)
			(layers "F.Cu" "F.Mask" "F.Paste")
			(net "P3V3_STBY")
		)
		(pad "E5" smd circle
			(at -2.800096 -2.800096 180)
			(size 0.3556 0.3556)
			(layers "F.Cu" "F.Mask" "F.Paste")
			(net "GND")
		)
		(pad "E6" smd circle
			(at -1.999996 -2.800096 180)
			(size 0.3556 0.3556)
			(layers "F.Cu" "F.Mask" "F.Paste")
			(net "FM_CPU1_FIVR_FAULT_LVT3_N")
		)
		(pad "E7" smd circle
			(at -1.199896 -2.800096 180)
			(size 0.3556 0.3556)
			(layers "F.Cu" "F.Mask" "F.Paste")
			(net "PWRGD_P1V15_BMC_STBY")
		)
		(pad "E8" smd circle
			(at -0.40005 -2.800096 180)
			(size 0.3556 0.3556)
			(layers "F.Cu" "F.Mask" "F.Paste")
			(net "TP_CPLD1_PT16B")
		)
		(pad "E9" smd circle
			(at 0.40005 -2.800096 180)
			(size 0.3556 0.3556)
			(layers "F.Cu" "F.Mask" "F.Paste")
			(net "FM_SLP_SUS_N")
		)
		(pad "E10" smd circle
			(at 1.199896 -2.800096 180)
			(size 0.3556 0.3556)
			(layers "F.Cu" "F.Mask" "F.Paste")
			(net "TP_CPLD1_PT20B")
		)
		(pad "E11" smd circle
			(at 1.999996 -2.800096 180)
			(size 0.3556 0.3556)
			(layers "F.Cu" "F.Mask" "F.Paste")
			(net "TP_CPLD1_PT19D")
		)
		(pad "E12" smd circle
			(at 2.800096 -2.800096 180)
			(size 0.3556 0.3556)
			(layers "F.Cu" "F.Mask" "F.Paste")
			(net "GND")
		)
		(pad "E13" smd circle
			(at 3.599942 -2.800096 180)
			(size 0.3556 0.3556)
			(layers "F.Cu" "F.Mask" "F.Paste")
			(net "P3V3_STBY")
		)
		(pad "E14" smd circle
			(at 4.400042 -2.800096 180)
			(size 0.3556 0.3556)
			(layers "F.Cu" "F.Mask" "F.Paste")
			(net "FM_CPLD_ADR_TRIGGER_N")
		)
		(pad "E15" smd circle
			(at 5.199888 -2.800096 180)
			(size 0.3556 0.3556)
			(layers "F.Cu" "F.Mask" "F.Paste")
			(net "RST_PLTRST_N")
		)
		(pad "E16" smd circle
			(at 5.999988 -2.800096 180)
			(size 0.3556 0.3556)
			(layers "F.Cu" "F.Mask" "F.Paste")
			(net "FM_P1V8MCP_CPU0_EN")
		)
		(pad "F1" smd circle
			(at -5.999988 -1.999996 180)
			(size 0.3556 0.3556)
			(layers "F.Cu" "F.Mask" "F.Paste")
			(net "FM_CPU0_PROC_ID0")
		)
		(pad "F2" smd circle
			(at -5.199888 -1.999996 180)
			(size 0.3556 0.3556)
			(layers "F.Cu" "F.Mask" "F.Paste")
			(net "FM_CPU0_PKGID0")
		)
		(pad "F3" smd circle
			(at -4.400042 -1.999996 180)
			(size 0.3556 0.3556)
			(layers "F.Cu" "F.Mask" "F.Paste")
			(net "FM_CPU0_PROC_ID1")
		)
		(pad "F4" smd circle
			(at -3.599942 -1.999996 180)
			(size 0.3556 0.3556)
			(layers "F.Cu" "F.Mask" "F.Paste")
			(net "PU_RST_PERST_BIT0")
		)
		(pad "F5" smd circle
			(at -2.800096 -1.999996 180)
			(size 0.3556 0.3556)
			(layers "F.Cu" "F.Mask" "F.Paste")
			(net "FM_CPU0_FIVR_FAULT_LVT3_N")
		)
		(pad "F6" smd circle
			(at -1.999996 -1.999996 180)
			(size 0.3556 0.3556)
			(layers "F.Cu" "F.Mask" "F.Paste")
			(net "GND")
		)
		(pad "F7" smd circle
			(at -1.199896 -1.999996 180)
			(size 0.3556 0.3556)
			(layers "F.Cu" "F.Mask" "F.Paste")
			(net "FM_PLD_DEBUG_MODE_N")
		)
		(pad "F8" smd circle
			(at -0.40005 -1.999996 180)
			(size 0.3556 0.3556)
			(layers "F.Cu" "F.Mask" "F.Paste")
			(net "SGPIO_BMC_DIN_R")
		)
		(pad "F9" smd circle
			(at 0.40005 -1.999996 180)
			(size 0.3556 0.3556)
			(layers "F.Cu" "F.Mask" "F.Paste")
			(net "FM_PS_EN")
		)
		(pad "F10" smd circle
			(at 1.199896 -1.999996 180)
			(size 0.3556 0.3556)
			(layers "F.Cu" "F.Mask" "F.Paste")
			(net "FM_CPU1_CD_PRES_N")
		)
		(pad "F11" smd circle
			(at 1.999996 -1.999996 180)
			(size 0.3556 0.3556)
			(layers "F.Cu" "F.Mask" "F.Paste")
			(net "GND")
		)
		(pad "F12" smd circle
			(at 2.800096 -1.999996 180)
			(size 0.3556 0.3556)
			(layers "F.Cu" "F.Mask" "F.Paste")
			(net "FM_P1V8MCP_CPU1_EN")
		)
		(pad "F13" smd circle
			(at 3.599942 -1.999996 180)
			(size 0.3556 0.3556)
			(layers "F.Cu" "F.Mask" "F.Paste")
			(net "PWRGD_CPUPWRGD")
		)
		(pad "F14" smd circle
			(at 4.400042 -1.999996 180)
			(size 0.3556 0.3556)
			(layers "F.Cu" "F.Mask" "F.Paste")
			(net "RST_BMC_SYSRST_BTN_OUT_B_R1_N")
		)
		(pad "F15" smd circle
			(at 5.199888 -1.999996 180)
			(size 0.3556 0.3556)
			(layers "F.Cu" "F.Mask" "F.Paste")
			(net "FM_CPU0_MCP_CLK_EN_N")
		)
		(pad "F16" smd circle
			(at 5.999988 -1.999996 180)
			(size 0.3556 0.3556)
			(layers "F.Cu" "F.Mask" "F.Paste")
			(net "FM_CPU1_MCP_CLK_EN_N")
		)
		(pad "G1" smd circle
			(at -5.999988 -1.199896 180)
			(size 0.3556 0.3556)
			(layers "F.Cu" "F.Mask" "F.Paste")
			(net "FM_SLPS3_N")
		)
		(pad "G2" smd circle
			(at -5.199888 -1.199896 180)
			(size 0.3556 0.3556)
			(layers "F.Cu" "F.Mask" "F.Paste")
			(net "FM_CPU0_PKGID2")
		)
		(pad "G3" smd circle
			(at -4.400042 -1.199896 180)
			(size 0.3556 0.3556)
			(layers "F.Cu" "F.Mask" "F.Paste")
			(net "FM_CPU0_PKGID1")
		)
		(pad "G4" smd circle
			(at -3.599942 -1.199896 180)
			(size 0.3556 0.3556)
			(layers "F.Cu" "F.Mask" "F.Paste")
			(net "RST_RSMRST_R_N")
		)
		(pad "G5" smd circle
			(at -2.800096 -1.199896 180)
			(size 0.3556 0.3556)
			(layers "F.Cu" "F.Mask" "F.Paste")
			(net "FM_DEBUG_RST_BTN_N")
		)
		(pad "G6" smd circle
			(at -1.999996 -1.199896 180)
			(size 0.3556 0.3556)
			(layers "F.Cu" "F.Mask" "F.Paste")
			(net "FM_PWR_BTN_R2_N")
		)
		(pad "G7" smd circle
			(at -1.199896 -1.199896 180)
			(size 0.3556 0.3556)
			(layers "F.Cu" "F.Mask" "F.Paste")
			(net "P3V3_STBY")
		)
		(pad "G8" smd circle
			(at -0.40005 -1.199896 180)
			(size 0.3556 0.3556)
			(layers "F.Cu" "F.Mask" "F.Paste")
			(net "P3V3_STBY")
		)
		(pad "G9" smd circle
			(at 0.40005 -1.199896 180)
			(size 0.3556 0.3556)
			(layers "F.Cu" "F.Mask" "F.Paste")
			(net "P3V3_STBY")
		)
		(pad "G10" smd circle
			(at 1.199896 -1.199896 180)
			(size 0.3556 0.3556)
			(layers "F.Cu" "F.Mask" "F.Paste")
			(net "P3V3_STBY")
		)
		(pad "G11" smd circle
			(at 1.999996 -1.199896 180)
			(size 0.3556 0.3556)
			(layers "F.Cu" "F.Mask" "F.Paste")
			(net "FM_WBG_PRSNT_N")
		)
		(pad "G12" smd circle
			(at 2.800096 -1.199896 180)
			(size 0.3556 0.3556)
			(layers "F.Cu" "F.Mask" "F.Paste")
			(net "FM_CPU0_THERMTRIP_LATCH_LVT3_N")
		)
	)
)
